# S9S_MB_2U (Grand Teton) — schematic netlist excerpt (pin names and nets, part order shuffled) for the footprints in the layout excerpt that follows; sources: Cadence DE-HDL packaged netlist, KiCad conversion of 03242023_DA0F0TMBIJ0_F0T_Motherboard_J_brd_V01_OCP.brd

PR2524  Q_RES  10 1% EMPTY  pkg 0402LF  page 304 : A = P12V_HSC_SENSE2_N ; B = P12V_HSC_SENSE2_R1_N
R58  Q_RES  0 5% CHIP  pkg 0402LF  page 45 : A = SVID_DIO1_CPU1 ; B = SVID_DIO1_CPU1_R

(kicad_pcb
	(version 20260206)
	(generator "pcbnew")
	(generator_version "10.0")
	(general
		(thickness 1.6)
		(legacy_teardrops no)
	)
	(paper "A4")
	(title_block
		(title "03242023_DA0F0TMBIJ0_F0T_Motherboard_J_brd_V01_OCP.brd")
		(comment 1 "Grand Teton / footprints 4780-4781 of 6105")
	)
	(layers
		(0 "F.Cu" signal "TOP")
		(4 "In1.Cu" signal "GND")
		(6 "In2.Cu" signal "IN1")
		(8 "In3.Cu" signal "GND1")
		(10 "In4.Cu" signal "IN2")
		(12 "In5.Cu" signal "GND2")
		(14 "In6.Cu" signal "IN3")
		(16 "In7.Cu" signal "GND3")
		(18 "In8.Cu" signal "VCC")
		(20 "In9.Cu" signal "VCC1")
		(22 "In10.Cu" signal "GND4")
		(24 "In11.Cu" signal "IN4")
		(26 "In12.Cu" signal "GND5")
		(28 "In13.Cu" signal "IN5")
		(30 "In14.Cu" signal "GND6")
		(32 "In15.Cu" signal "IN6")
		(34 "In16.Cu" signal "GND7")
		(2 "B.Cu" signal "BOTTOM")
		(9 "F.Adhes" user "F.Adhesive")
		(11 "B.Adhes" user "B.Adhesive")
		(13 "F.Paste" user "Package Geometry/Pastemask Top")
		(15 "B.Paste" user "Package Geometry/Pastemask Bottom")
		(5 "F.SilkS" user "Ref Des/Silkscreen Top")
		(7 "B.SilkS" user "Ref Des/Silkscreen Bottom")
		(1 "F.Mask" user "Board Geometry/Soldermask Top")
		(3 "B.Mask" user "Board Geometry/Soldermask Bottom")
		(17 "Dwgs.User" user "User.Drawings")
		(19 "Cmts.User" user "User.Comments")
		(21 "Eco1.User" user "User.Eco1")
		(23 "Eco2.User" user "User.Eco2")
		(25 "Edge.Cuts" user "Board Geometry/Outline")
		(27 "Margin" user)
		(31 "F.CrtYd" user "Package Geometry/Place Bound Top")
		(29 "B.CrtYd" user "Package Geometry/Place Bound Bottom")
		(35 "F.Fab" user "Ref Des/Assembly Top")
		(33 "B.Fab" user "Ref Des/Assembly Bottom")
	)
	(footprint ""
		(layer "B.Cu")
		(at 72.401684 -190.744856 90)
		(property "Reference" "R58"
			(at 0 0 90)
			(layer "B.SilkS")
			(hide yes)
			(effects
				(font
					(size 1.27 1.27)
				)
				(justify mirror)
			)
		)
		(property "Value" ""
			(at 0 0 90)
			(layer "B.Fab")
			(effects
				(font
					(size 1.27 1.27)
				)
				(justify mirror)
			)
		)
		(duplicate_pad_numbers_are_jumpers no)
		(fp_line
			(start 0.7874 -0.4064)
			(end -0.7874 -0.4064)
			(stroke
				(width 0.1524)
				(type default)
			)
			(layer "B.SilkS")
		)
		(fp_line
			(start -0.7874 -0.4064)
			(end -0.7874 0.4064)
			(stroke
				(width 0.1524)
				(type default)
			)
			(layer "B.SilkS")
		)
		(fp_line
			(start 0.7874 0.4064)
			(end 0.7874 -0.4064)
			(stroke
				(width 0.1524)
				(type default)
			)
			(layer "B.SilkS")
		)
		(fp_line
			(start -0.7874 0.4064)
			(end 0.7874 0.4064)
			(stroke
				(width 0.1524)
				(type default)
			)
			(layer "B.SilkS")
		)
		(fp_line
			(start 0.67945 -0.305054)
			(end 0.12065 -0.305054)
			(stroke
				(width 0.1)
				(type default)
			)
			(layer "B.Fab")
		)
		(fp_line
			(start 0.12065 -0.305054)
			(end 0.12065 -0.2794)
			(stroke
				(width 0.1)
				(type default)
			)
			(layer "B.Fab")
		)
		(fp_line
			(start -0.12065 -0.3048)
			(end -0.67945 -0.3048)
			(stroke
				(width 0.1)
				(type default)
			)
			(layer "B.Fab")
		)
		(fp_line
			(start -0.67945 -0.3048)
			(end -0.67945 0.3048)
			(stroke
				(width 0.1)
				(type default)
			)
			(layer "B.Fab")
		)
		(fp_line
			(start 0.12065 -0.2794)
			(end -0.12065 -0.2794)
			(stroke
				(width 0.1)
				(type default)
			)
			(layer "B.Fab")
		)
		(fp_line
			(start -0.12065 -0.2794)
			(end -0.12065 -0.3048)
			(stroke
				(width 0.1)
				(type default)
			)
			(layer "B.Fab")
		)
		(fp_line
			(start 0.12065 0.2794)
			(end 0.12065 0.3048)
			(stroke
				(width 0.1)
				(type default)
			)
			(layer "B.Fab")
		)
		(fp_line
			(start -0.120396 0.2794)
			(end 0.12065 0.2794)
			(stroke
				(width 0.1)
				(type default)
			)
			(layer "B.Fab")
		)
		(fp_line
			(start 0.67945 0.3048)
			(end 0.67945 -0.305054)
			(stroke
				(width 0.1)
				(type default)
			)
			(layer "B.Fab")
		)
		(fp_line
			(start 0.12065 0.3048)
			(end 0.67945 0.3048)
			(stroke
				(width 0.1)
				(type default)
			)
			(layer "B.Fab")
		)
		(fp_line
			(start -0.120396 0.3048)
			(end -0.120396 0.2794)
			(stroke
				(width 0.1)
				(type default)
			)
			(layer "B.Fab")
		)
		(fp_line
			(start -0.67945 0.3048)
			(end -0.120396 0.3048)
			(stroke
				(width 0.1)
				(type default)
			)
			(layer "B.Fab")
		)
		(pad "1" smd circle
			(at 0.40005 0 270)
			(size 0 0)
			(layers "B.Cu" "B.Mask" "B.Paste")
			(net "SVID_DIO1_CPU1")
		)
		(pad "2" smd circle
			(at -0.40005 0 270)
			(size 0 0)
			(layers "B.Cu" "B.Mask" "B.Paste")
			(net "SVID_DIO1_CPU1_R")
		)
	)
	(footprint ""
		(layer "B.Cu")
		(at 297.45813 -400.999452 -90)
		(property "Reference" "PR2524"
			(at 0 0 90)
			(layer "B.SilkS")
			(hide yes)
			(effects
				(font
					(size 1.27 1.27)
				)
				(justify mirror)
			)
		)
		(property "Value" ""
			(at 0 0 90)
			(layer "B.Fab")
			(effects
				(font
					(size 1.27 1.27)
				)
				(justify mirror)
			)
		)
		(duplicate_pad_numbers_are_jumpers no)
		(fp_line
			(start -0.7874 0.4064)
			(end 0.7874 0.4064)
			(stroke
				(width 0.1524)
				(type default)
			)
			(layer "B.SilkS")
		)
		(fp_line
			(start 0.7874 0.4064)
			(end 0.7874 -0.4064)
			(stroke
				(width 0.1524)
				(type default)
			)
			(layer "B.SilkS")
		)
		(fp_line
			(start -0.7874 -0.4064)
			(end -0.7874 0.4064)
			(stroke
				(width 0.1524)
				(type default)
			)
			(layer "B.SilkS")
		)
		(fp_line
			(start 0.7874 -0.4064)
			(end -0.7874 -0.4064)
			(stroke
				(width 0.1524)
				(type default)
			)
			(layer "B.SilkS")
		)
		(fp_line
			(start -0.67945 0.3048)
			(end -0.120396 0.3048)
			(stroke
				(width 0.1)
				(type default)
			)
			(layer "B.Fab")
		)
		(fp_line
			(start -0.120396 0.3048)
			(end -0.120396 0.2794)
			(stroke
				(width 0.1)
				(type default)
			)
			(layer "B.Fab")
		)
		(fp_line
			(start 0.12065 0.3048)
			(end 0.67945 0.3048)
			(stroke
				(width 0.1)
				(type default)
			)
			(layer "B.Fab")
		)
		(fp_line
			(start 0.67945 0.3048)
			(end 0.67945 -0.305054)
			(stroke
				(width 0.1)
				(type default)
			)
			(layer "B.Fab")
		)
		(fp_line
			(start -0.120396 0.2794)
			(end 0.12065 0.2794)
			(stroke
				(width 0.1)
				(type default)
			)
			(layer "B.Fab")
		)
		(fp_line
			(start 0.12065 0.2794)
			(end 0.12065 0.3048)
			(stroke
				(width 0.1)
				(type default)
			)
			(layer "B.Fab")
		)
		(fp_line
			(start -0.12065 -0.2794)
			(end -0.12065 -0.3048)
			(stroke
				(width 0.1)
				(type default)
			)
			(layer "B.Fab")
		)
		(fp_line
			(start 0.12065 -0.2794)
			(end -0.12065 -0.2794)
			(stroke
				(width 0.1)
				(type default)
			)
			(layer "B.Fab")
		)
		(fp_line
			(start -0.67945 -0.3048)
			(end -0.67945 0.3048)
			(stroke
				(width 0.1)
				(type default)
			)
			(layer "B.Fab")
		)
		(fp_line
			(start -0.12065 -0.3048)
			(end -0.67945 -0.3048)
			(stroke
				(width 0.1)
				(type default)
			)
			(layer "B.Fab")
		)
		(fp_line
			(start 0.12065 -0.305054)
			(end 0.12065 -0.2794)
			(stroke
				(width 0.1)
				(type default)
			)
			(layer "B.Fab")
		)
		(fp_line
			(start 0.67945 -0.305054)
			(end 0.12065 -0.305054)
			(stroke
				(width 0.1)
				(type default)
			)
			(layer "B.Fab")
		)
		(pad "1" smd circle
			(at 0.40005 0 90)
			(size 0 0)
			(layers "B.Cu" "B.Mask" "B.Paste")
			(net "P12V_HSC_SENSE2_N")
		)
		(pad "2" smd circle
			(at -0.40005 0 90)
			(size 0 0)
			(layers "B.Cu" "B.Mask" "B.Paste")
			(net "P12V_HSC_SENSE2_R1_N")
		)
	)
)
